# S9S_MB_2U (Grand Teton) — schematic parts with pin connectivity, parts 5880–5880 of 6093; source: Cadence DE-HDL packaged netlist (pstxprt.dat, pstxnet.dat, pstchip.dat)

U2  SOCKET4677_AZIF0045P001C01CS  SOCKET4677_AZIF0045-P001C01CS IO  pkg SOCKET4677_82X64-5XA_H466  page 13  (pins 327-652 of 4677)
  AG62  DDR2_SA_DQ27  BI  = M_C_CPU0_SA_DQ<27>
  AG64  VSS144  POWER  = GND
  AG66  DDR2_SA_DQ14  BI  = M_C_CPU0_SA_DQ<14>
  AG68  DDR2_SA_DQ11  BI  = M_C_CPU0_SA_DQ<11>
  AG70  VSS145  POWER  = GND
  AG72  DDR3_SA_DQ6  BI  = M_D_CPU0_SA_DQ<6>
  AG74  DDR3_SA_DQ3  BI  = M_D_CPU0_SA_DQ<3>
  AG76  VSS146  POWER  = GND
  AG78  VCCFA_EHV_FIVRA9  POWER  = PVCCFA_EHV_FIVRA_CPU0
  AG80  UPI2_RX_DP8  IN  = UPI_CPU1_CPU0_P2P2_DN<15>
  AG82  UPI2_RX_DN11  IN  = UPI_CPU1_CPU0_P2P2_DP<12>
  AG84  VSS147  POWER  = GND
  AG86  PE4_TX_DN8  OUT  = P5E_CPU0_PE4_TX_DN<8>
  AG88  VSS148  POWER  = GND
  AG90  PE4_RX_DP8  IN  = P5E_CPU0_PE4_RX_DP<8>
  AH2  UPI0_TX_DN9  OUT  = UPI_CPU0_CPU1_P0P1_DN<9>
  AH4  VSS159  POWER  = GND
  AH6  UPI0_RX_DN9  IN  = UPI_CPU1_CPU0_P1P0_DN<9>
  AH8  VSS174  POWER  = GND
  AH10  PE0_RX_DP9  IN  = P5E_CPU0_PE0_RX_DP<9>
  AH12  VSS150  POWER  = GND
  AH14  PE0_TX_DP8  OUT  = P5E_CPU0_PE0_TX_DP<8>
  AH16  VSS151  POWER  = GND
  AH18  DDR2_SB_DQS_DP8  BI  = M_C_CPU0_SB_DQS_DP<8>
  AH20  VSS152  POWER  = GND
  AH22  VSS153  POWER  = GND
  AH24  DDR3_SB_DQS_DP7  BI  = M_D_CPU0_SB_DQS_DP<7>
  AH26  VSS154  POWER  = GND
  AH28  VSS155  POWER  = GND
  AH30  DDR2_SB_DQS_DP6  BI  = M_C_CPU0_SB_DQS_DP<6>
  AH32  VSS156  POWER  = GND
  AH34  VSS157  POWER  = GND
  AH36  DDR2_SB_DQS_DP5  BI  = M_C_CPU0_SB_DQS_DP<5>
  AH38  VSS158  POWER  = GND
  AH40  VSS160  POWER  = GND
  AH42  DDR3_SB_PAR  OUT  = M_D_CPU0_SB_PAR
  AH44  VSS161  POWER  = GND
  AH47  VSS162  POWER  = GND
  AH49  DDR2_CLK_DP1  OUT  = M_C_CPU0_CLK_DP<1>
  AH51  VSS163  POWER  = GND
  AH53  VSS164  POWER  = GND
  AH55  DDR2_SA_DQS_DN9  BI  = M_C_CPU0_SA_DQS_DN<9>
  AH57  VSS165  POWER  = GND
  AH59  VSS166  POWER  = GND
  AH61  DDR2_SA_DQS_DP8  BI  = M_C_CPU0_SA_DQS_DP<8>
  AH63  VSS167  POWER  = GND
  AH65  VSS168  POWER  = GND
  AH67  DDR2_SA_DQS_DN6  BI  = M_C_CPU0_SA_DQS_DN<6>
  AH69  VSS169  POWER  = GND
  AH71  VSS170  POWER  = GND
  AH73  DDR3_SA_DQS_DN5  BI  = M_D_CPU0_SA_DQS_DN<5>
  AH75  VSS171  POWER  = GND
  AH77  VSS172  POWER  = GND
  AH79  VSS173  POWER  = GND
  AH81  UPI2_RX_DP10  IN  = UPI_CPU1_CPU0_P2P2_DP<13>
  AH83  VSS175  POWER  = GND
  AH85  VCCFA_EHV_FIVRA10  POWER  = PVCCFA_EHV_FIVRA_CPU0
  AH87  PE4_TX_DP8  OUT  = P5E_CPU0_PE4_TX_DP<8>
  AH89  VCCFA_EHV_FIVRA11  POWER  = PVCCFA_EHV_FIVRA_CPU0
  AH91  PE4_RX_DN8  IN  = P5E_CPU0_PE4_RX_DN<8>
  AJ1  UPI0_TX_DP10  OUT  = UPI_CPU0_CPU1_P0P1_DP<10>
  AJ3  VCCFA_EHV2  POWER  = PVCCFA_EHV_CPU0
  AJ5  UPI0_RX_DP9  IN  = UPI_CPU1_CPU0_P1P0_DP<9>
  AJ7  VCCFA_EHV_FIVRA14  POWER  = PVCCFA_EHV_FIVRA_CPU0
  AJ9  PE0_RX_DN9  IN  = P5E_CPU0_PE0_RX_DN<9>
  AJ11  VCCFA_EHV_FIVRA12  POWER  = PVCCFA_EHV_FIVRA_CPU0
  AJ13  PE0_TX_DN8  OUT  = P5E_CPU0_PE0_TX_DN<8>
  AJ15  VCCFA_EHV_FIVRA13  POWER  = PVCCFA_EHV_FIVRA_CPU0
  AJ17  DDR2_SB_DQ31  BI  = M_C_CPU0_SB_DQ<31>
  AJ19  VSS176  POWER  = GND
  AJ21  DDR3_SB_DQS_DN3  BI  = M_D_CPU0_SB_DQS_DN<3>
  AJ23  VSS177  POWER  = GND
  AJ25  VSS178  POWER  = GND
  AJ27  DDR3_SB_DQS_DN1  BI  = M_D_CPU0_SB_DQS_DN<1>
  AJ29  VSS179  POWER  = GND
  AJ31  VSS180  POWER  = GND
  AJ33  DDR3_SB_DQS_DN0  BI  = M_D_CPU0_SB_DQS_DN<0>
  AJ35  VSS181  POWER  = GND
  AJ37  VSS182  POWER  = GND
  AJ39  DDR3_SB_DQS_DN9  BI  = M_D_CPU0_SB_DQS_DN<9>
  AJ41  VSS183  POWER  = GND
  AJ43  VSS184  POWER  = GND
  AJ45  DDR3_CLK_DN0  OUT  = M_D_CPU0_CLK_DN<0>
  AJ48  VSS185  POWER  = GND
  AJ50  VSS186  POWER  = GND
  AJ52  DDR3_SA_CA0  OUT  = M_D_CPU0_SA_CA<0>
  AJ54  VSS187  POWER  = GND
  AJ56  VSS188  POWER  = GND
  AJ58  DDR3_SA_DQS_DN4  BI  = M_D_CPU0_SA_DQS_DN<4>
  AJ60  VSS189  POWER  = GND
  AJ62  VSS190  POWER  = GND
  AJ64  DDR3_SA_DQS_DN3  BI  = M_D_CPU0_SA_DQS_DN<3>
  AJ66  VSS191  POWER  = GND
  AJ68  VSS192  POWER  = GND
  AJ70  DDR3_SA_DQS_DN2  BI  = M_D_CPU0_SA_DQS_DN<2>
  AJ72  VSS193  POWER  = GND
  AJ74  VSS194  POWER  = GND
  AJ76  DDR3_SA_DQS_DN1  BI  = M_D_CPU0_SA_DQS_DN<1>
  AJ78  VSS195  POWER  = GND
  AJ80  UPI2_RX_DN10  IN  = UPI_CPU1_CPU0_P2P2_DN<13>
  AJ82  UPI2_RX_DP11  IN  = UPI_CPU1_CPU0_P2P2_DN<12>
  AJ84  VSS196  POWER  = GND
  AJ86  PE4_TX_DN9  OUT  = P5E_CPU0_PE4_TX_DN<9>
  AJ88  VSS197  POWER  = GND
  AJ90  PE4_RX_DP9  IN  = P5E_CPU0_PE4_RX_DP<9>
  AK2  UPI0_TX_DN10  OUT  = UPI_CPU0_CPU1_P0P1_DN<10>
  AK4  VSS204  POWER  = GND
  AK6  UPI0_RX_DN10  IN  = UPI_CPU1_CPU0_P1P0_DP<10>
  AK8  VSS212  POWER  = GND
  AK10  PE0_RX_DN10  IN  = P5E_CPU0_PE0_RX_DN<10>
  AK12  VSS198  POWER  = GND
  AK14  PE0_TX_DN9  OUT  = P5E_CPU0_PE0_TX_DN<9>
  AK16  VSS199  POWER  = GND
  AK18  VSS200  POWER  = GND
  AK20  DDR3_SB_DQ28  BI  = M_D_CPU0_SB_DQ<28>
  AK22  DDR3_SB_DQ25  BI  = M_D_CPU0_SB_DQ<25>
  AK24  VSS201  POWER  = GND
  AK26  DDR3_SB_DQ12  BI  = M_D_CPU0_SB_DQ<12>
  AK28  DDR3_SB_DQ9  BI  = M_D_CPU0_SB_DQ<9>
  AK30  VSS202  POWER  = GND
  AK32  DDR3_SB_DQ4  BI  = M_D_CPU0_SB_DQ<4>
  AK34  DDR3_SB_DQ1  BI  = M_D_CPU0_SB_DQ<1>
  AK36  VSS203  POWER  = GND
  AK38  DDR3_SB_ECC0  BI  = M_D_CPU0_SB_CB<0>
  AK40  DDR3_SB_ECC5  BI  = M_D_CPU0_SB_CB<5>
  AK42  VSS205  POWER  = GND
  AK44  DDR3_SB_CA0  OUT  = M_D_CPU0_SB_CA<0>
  AK47  DDR1_A_RSP1  IN  = M_B_CPU0_SA_RSP<1>
  AK49  VSS206  POWER  = GND
  AK51  DDR3_SA_CA2  OUT  = M_D_CPU0_SA_CA<2>
  AK53  DDR3_SA_CS_N1  OUT  = M_D_CPU0_SA_CS_N<1>
  AK55  VSS207  POWER  = GND
  AK57  DDR3_SA_ECC4  BI  = M_D_CPU0_SA_CB<4>
  AK59  DDR3_SA_ECC1  BI  = M_D_CPU0_SA_CB<1>
  AK61  VSS208  POWER  = GND
  AK63  DDR3_SA_DQ28  BI  = M_D_CPU0_SA_DQ<28>
  AK65  DDR3_SA_DQ25  BI  = M_D_CPU0_SA_DQ<25>
  AK67  VSS209  POWER  = GND
  AK69  DDR3_SA_DQ20  BI  = M_D_CPU0_SA_DQ<20>
  AK71  DDR3_SA_DQ17  BI  = M_D_CPU0_SA_DQ<17>
  AK73  VSS210  POWER  = GND
  AK75  DDR3_SA_DQ12  BI  = M_D_CPU0_SA_DQ<12>
  AK77  DDR3_SA_DQ9  BI  = M_D_CPU0_SA_DQ<9>
  AK79  VSS211  POWER  = GND
  AK81  VSS213  POWER  = GND
  AK83  VSS214  POWER  = GND
  AK85  PE4_TX_DP9  OUT  = P5E_CPU0_PE4_TX_DP<9>
  AK87  VSS215  POWER  = GND
  AK89  PE4_RX_DN9  IN  = P5E_CPU0_PE4_RX_DN<9>
  AK91  VSS216  POWER  = GND
  AL1  VSS217  POWER  = GND
  AL3  UPI0_TX_DP11  OUT  = UPI_CPU0_CPU1_P0P1_DP<11>
  AL5  VSS220  POWER  = GND
  AL7  UPI0_RX_DP10  IN  = UPI_CPU1_CPU0_P1P0_DN<10>
  AL9  VSS226  POWER  = GND
  AL11  PE0_RX_DP10  IN  = P5E_CPU0_PE0_RX_DP<10>
  AL13  VSS218  POWER  = GND
  AL15  PE0_TX_DP9  OUT  = P5E_CPU0_PE0_TX_DP<9>
  AL17  VSS219  POWER  = GND
  AL19  DDR3_SB_DQ29  BI  = M_D_CPU0_SB_DQ<29>
  AL21  DDR3_SB_DQS_DP3  BI  = M_D_CPU0_SB_DQS_DP<3>
  AL23  DDR3_SB_DQ24  BI  = M_D_CPU0_SB_DQ<24>
  AL25  DDR3_SB_DQ13  BI  = M_D_CPU0_SB_DQ<13>
  AL27  DDR3_SB_DQS_DP1  BI  = M_D_CPU0_SB_DQS_DP<1>
  AL29  DDR3_SB_DQ8  BI  = M_D_CPU0_SB_DQ<8>
  AL31  DDR3_SB_DQ5  BI  = M_D_CPU0_SB_DQ<5>
  AL33  DDR3_SB_DQS_DP0  BI  = M_D_CPU0_SB_DQS_DP<0>
  AL35  DDR3_SB_DQ0  BI  = M_D_CPU0_SB_DQ<0>
  AL37  DDR3_SB_ECC1  BI  = M_D_CPU0_SB_CB<1>
  AL39  DDR3_SB_DQS_DP9  BI  = M_D_CPU0_SB_DQS_DP<9>
  AL41  DDR3_SB_ECC4  BI  = M_D_CPU0_SB_CB<4>
  AL43  DDR3_SB_CA1  OUT  = M_D_CPU0_SB_CA<1>
  AL45  DDR3_CLK_DP0  OUT  = M_D_CPU0_CLK_DP<0>
  AL48  DDR1_A_RSP0  IN  = M_B_CPU0_SA_RSP<0>
  AL50  DDR3_SA_CA4  OUT  = M_D_CPU0_SA_CA<4>
  AL52  VSS221  POWER  = GND
  AL54  DDR3_SA_CS_N0  OUT  = M_D_CPU0_SA_CS_N<0>
  AL56  DDR3_SA_ECC5  BI  = M_D_CPU0_SA_CB<5>
  AL58  DDR3_SA_DQS_DP4  BI  = M_D_CPU0_SA_DQS_DP<4>
  AL60  DDR3_SA_ECC0  BI  = M_D_CPU0_SA_CB<0>
  AL62  DDR3_SA_DQ29  BI  = M_D_CPU0_SA_DQ<29>
  AL64  DDR3_SA_DQS_DP3  BI  = M_D_CPU0_SA_DQS_DP<3>
  AL66  DDR3_SA_DQ24  BI  = M_D_CPU0_SA_DQ<24>
  AL68  DDR3_SA_DQ21  BI  = M_D_CPU0_SA_DQ<21>
  AL70  DDR3_SA_DQS_DP2  BI  = M_D_CPU0_SA_DQS_DP<2>
  AL72  DDR3_SA_DQ16  BI  = M_D_CPU0_SA_DQ<16>
  AL74  DDR3_SA_DQ13  BI  = M_D_CPU0_SA_DQ<13>
  AL76  DDR3_SA_DQS_DP1  BI  = M_D_CPU0_SA_DQS_DP<1>
  AL78  DDR3_SA_DQ8  BI  = M_D_CPU0_SA_DQ<8>
  AL80  VSS222  POWER  = GND
  AL82  VSS223  POWER  = GND
  AL84  VSS224  POWER  = GND
  AL86  PE4_TX_DN10  OUT  = P5E_CPU0_PE4_TX_DN<10>
  AL88  VSS225  POWER  = GND
  AL90  PE4_RX_DP10  IN  = P5E_CPU0_PE4_RX_DP<10>
  AM2  UPI0_TX_DN11  OUT  = UPI_CPU0_CPU1_P0P1_DN<11>
  AM4  VSS240  POWER  = GND
  AM6  UPI0_RX_DP11  IN  = UPI_CPU1_CPU0_P1P0_DN<11>
  AM8  VSS260  POWER  = GND
  AM10  PE0_RX_DN11  IN  = P5E_CPU0_PE0_RX_DN<11>
  AM12  VSS227  POWER  = GND
  AM14  PE0_TX_DP10  OUT  = P5E_CPU0_PE0_TX_DP<10>
  AM16  VSS228  POWER  = GND
  AM18  VSS229  POWER  = GND
  AM20  VSS230  POWER  = GND
  AM22  VSS231  POWER  = GND
  AM24  VSS232  POWER  = GND
  AM26  VSS233  POWER  = GND
  AM28  VSS234  POWER  = GND
  AM30  VSS235  POWER  = GND
  AM32  VSS236  POWER  = GND
  AM34  VSS237  POWER  = GND
  AM36  VSS238  POWER  = GND
  AM38  VSS239  POWER  = GND
  AM40  VSS241  POWER  = GND
  AM42  VSS242  POWER  = GND
  AM44  VSS243  POWER  = GND
  AM47  VSS244  POWER  = GND
  AM49  VSS245  POWER  = GND
  AM51  VSS246  POWER  = GND
  AM53  VSS247  POWER  = GND
  AM55  VSS248  POWER  = GND
  AM57  VSS249  POWER  = GND
  AM59  VSS250  POWER  = GND
  AM61  VSS251  POWER  = GND
  AM63  VSS252  POWER  = GND
  AM65  VSS253  POWER  = GND
  AM67  VSS254  POWER  = GND
  AM69  VSS255  POWER  = GND
  AM71  VSS256  POWER  = GND
  AM73  VSS257  POWER  = GND
  AM75  VSS258  POWER  = GND
  AM77  VSS259  POWER  = GND
  AM79  VCCFA_EHV_FIVRA15  POWER  = PVCCFA_EHV_FIVRA_CPU0
  AM81  UPI2_TX_DN12  OUT  = UPI_CPU0_CPU1_P2P2_DN<11>
  AM83  UPI2_TX_DP13  OUT  = UPI_CPU0_CPU1_P2P2_DP<10>
  AM85  VCCFA_EHV_FIVRA16  POWER  = PVCCFA_EHV_FIVRA_CPU0
  AM87  PE4_TX_DP10  OUT  = P5E_CPU0_PE4_TX_DP<10>
  AM89  VCCFA_EHV_FIVRA17  POWER  = PVCCFA_EHV_FIVRA_CPU0
  AM91  PE4_RX_DN10  IN  = P5E_CPU0_PE4_RX_DN<10>
  AN1  UPI0_TX_DP12  OUT  = UPI_CPU0_CPU1_P0P1_DN<12>
  AN3  VCCFA_EHV3  POWER  = PVCCFA_EHV_CPU0
  AN5  UPI0_RX_DN11  IN  = UPI_CPU1_CPU0_P1P0_DP<11>
  AN7  VCCFA_EHV_FIVRA20  POWER  = PVCCFA_EHV_FIVRA_CPU0
  AN9  PE0_RX_DP11  IN  = P5E_CPU0_PE0_RX_DP<11>
  AN11  VCCFA_EHV_FIVRA18  POWER  = PVCCFA_EHV_FIVRA_CPU0
  AN13  PE0_TX_DN10  OUT  = P5E_CPU0_PE0_TX_DN<10>
  AN15  VCCFA_EHV_FIVRA19  POWER  = PVCCFA_EHV_FIVRA_CPU0
  AN17  RSVD2  BI  = NC_CPU0_UPI0_APROBE<0>
  AN19  DDR3_SB_DQ31  BI  = M_D_CPU0_SB_DQ<31>
  AN21  DDR3_SB_DQS_DN8  BI  = M_D_CPU0_SB_DQS_DN<8>
  AN23  DDR3_SB_DQ26  BI  = M_D_CPU0_SB_DQ<26>
  AN25  DDR3_SB_DQ15  BI  = M_D_CPU0_SB_DQ<15>
  AN27  DDR3_SB_DQS_DN6  BI  = M_D_CPU0_SB_DQS_DN<6>
  AN29  DDR3_SB_DQ10  BI  = M_D_CPU0_SB_DQ<10>
  AN31  DDR3_SB_DQ7  BI  = M_D_CPU0_SB_DQ<7>
  AN33  DDR3_SB_DQS_DN5  BI  = M_D_CPU0_SB_DQS_DN<5>
  AN35  DDR3_SB_DQ2  BI  = M_D_CPU0_SB_DQ<2>
  AN37  DDR3_SB_ECC3  BI  = M_D_CPU0_SB_CB<3>
  AN39  DDR3_SB_DQS_DP4  BI  = M_D_CPU0_SB_DQS_DP<4>
  AN41  DDR3_SB_ECC6  BI  = M_D_CPU0_SB_CB<6>
  AN43  DDR3_SA_CA6  OUT  = M_D_CPU0_SA_CA<6>
  AN45  DDR3_CLK_DN1  OUT  = M_D_CPU0_CLK_DN<1>
  AN48  DDR1_B_RSP0  IN  = M_B_CPU0_SB_RSP<0>
  AN50  DDR3_SA_CA5  OUT  = M_D_CPU0_SA_CA<5>
  AN52  VSS261  POWER  = GND
  AN54  DDR3_SA_CS_N2  OUT  = M_D_CPU0_SA_CS_N<2>
  AN56  DDR3_SA_ECC7  BI  = M_D_CPU0_SA_CB<7>
  AN58  DDR3_SA_DQS_DN9  BI  = M_D_CPU0_SA_DQS_DN<9>
  AN60  DDR3_SA_ECC2  BI  = M_D_CPU0_SA_CB<2>
  AN62  DDR3_SA_DQ31  BI  = M_D_CPU0_SA_DQ<31>
  AN64  DDR3_SA_DQS_DN8  BI  = M_D_CPU0_SA_DQS_DN<8>
  AN66  DDR3_SA_DQ26  BI  = M_D_CPU0_SA_DQ<26>
  AN68  DDR3_SA_DQ23  BI  = M_D_CPU0_SA_DQ<23>
  AN70  DDR3_SA_DQS_DN7  BI  = M_D_CPU0_SA_DQS_DN<7>
  AN72  DDR3_SA_DQ18  BI  = M_D_CPU0_SA_DQ<18>
  AN74  DDR3_SA_DQ15  BI  = M_D_CPU0_SA_DQ<15>
  AN76  DDR3_SA_DQS_DN6  BI  = M_D_CPU0_SA_DQS_DN<6>
  AN78  DDR3_SA_DQ10  BI  = M_D_CPU0_SA_DQ<10>
  AN80  VCCFA_EHV_FIVRA21  POWER  = PVCCFA_EHV_FIVRA_CPU0
  AN82  UPI2_TX_DN13  OUT  = UPI_CPU0_CPU1_P2P2_DN<10>
  AN84  VSS262  POWER  = GND
  AN86  PE4_TX_DP11  OUT  = P5E_CPU0_PE4_TX_DP<11>
  AN88  VSS263  POWER  = GND
  AN90  PE4_RX_DP11  IN  = P5E_CPU0_PE4_RX_DP<11>
  AP2  UPI0_TX_DN12  OUT  = UPI_CPU0_CPU1_P0P1_DP<12>
  AP4  VSS270  POWER  = GND
  AP6  UPI0_RX_DN12  IN  = UPI_CPU1_CPU0_P1P0_DP<12>
  AP8  VSS278  POWER  = GND
  AP10  PE0_RX_DN12  IN  = P5E_CPU0_PE0_RX_DN<12>
  AP12  VSS264  POWER  = GND
  AP14  PE0_TX_DN11  OUT  = P5E_CPU0_PE0_TX_DN<11>
  AP16  VSS265  POWER  = GND
  AP18  VSS266  POWER  = GND
  AP20  DDR3_SB_DQ30  BI  = M_D_CPU0_SB_DQ<30>
  AP22  DDR3_SB_DQ27  BI  = M_D_CPU0_SB_DQ<27>
  AP24  VSS267  POWER  = GND
  AP26  DDR3_SB_DQ14  BI  = M_D_CPU0_SB_DQ<14>
  AP28  DDR3_SB_DQ11  BI  = M_D_CPU0_SB_DQ<11>
  AP30  VSS268  POWER  = GND
  AP32  DDR3_SB_DQ6  BI  = M_D_CPU0_SB_DQ<6>
  AP34  DDR3_SB_DQ3  BI  = M_D_CPU0_SB_DQ<3>
  AP36  VSS269  POWER  = GND
  AP38  DDR3_SB_ECC2  BI  = M_D_CPU0_SB_CB<2>
  AP40  DDR3_SB_ECC7  BI  = M_D_CPU0_SB_CB<7>
  AP42  VSS271  POWER  = GND
  AP44  DDR3_SA_PAR  OUT  = M_D_CPU0_SA_PAR
  AP47  DDR1_B_RSP1  IN  = M_B_CPU0_SB_RSP<1>
  AP49  VSS272  POWER  = GND
  AP51  DDR3_SA_CA3  OUT  = M_D_CPU0_SA_CA<3>
  AP53  DDR3_SA_CS_N3  OUT  = M_D_CPU0_SA_CS_N<3>
  AP55  VSS273  POWER  = GND
  AP57  DDR3_SA_ECC6  BI  = M_D_CPU0_SA_CB<6>
  AP59  DDR3_SA_ECC3  BI  = M_D_CPU0_SA_CB<3>
  AP61  VSS274  POWER  = GND
  AP63  DDR3_SA_DQ30  BI  = M_D_CPU0_SA_DQ<30>
  AP65  DDR3_SA_DQ27  BI  = M_D_CPU0_SA_DQ<27>
  AP67  VSS275  POWER  = GND
  AP69  DDR3_SA_DQ22  BI  = M_D_CPU0_SA_DQ<22>
  AP71  DDR3_SA_DQ19  BI  = M_D_CPU0_SA_DQ<19>
  AP73  VSS276  POWER  = GND
  AP75  DDR3_SA_DQ14  BI  = M_D_CPU0_SA_DQ<14>
  AP77  DDR3_SA_DQ11  BI  = M_D_CPU0_SA_DQ<11>
  AP79  VSS277  POWER  = GND
  AP81  UPI2_TX_DP12  OUT  = UPI_CPU0_CPU1_P2P2_DP<11>
  AP83  VSS279  POWER  = GND
